(kicad_pcb
	(version 20260206)
	(generator "pcbnew")
	(generator_version "10.0")
	(general
		(thickness 1.6)
		(legacy_teardrops no)
	)
	(paper "A4")
	(title_block
		(title "v1-pdb — T6M_PDB_D_0927_0900.brd")
		(comment 1 "Open CloudServer (Microsoft) / footprints 282-283 of 321")
	)
	(layers
		(0 "F.Cu" signal "TOP")
		(4 "In1.Cu" signal "GND")
		(6 "In2.Cu" signal "IN1")
		(8 "In3.Cu" signal "VCC")
		(10 "In4.Cu" signal "VCC1")
		(12 "In5.Cu" signal "IN2")
		(14 "In6.Cu" signal "GND1")
		(2 "B.Cu" signal "BOTTOM")
		(9 "F.Adhes" user "F.Adhesive")
		(11 "B.Adhes" user "B.Adhesive")
		(13 "F.Paste" user "Package Geometry/Pastemask Top")
		(15 "B.Paste" user "Package Geometry/Pastemask Bottom")
		(5 "F.SilkS" user "Ref Des/Silkscreen Top")
		(7 "B.SilkS" user "Ref Des/Silkscreen Bottom")
		(1 "F.Mask" user "Board Geometry/Soldermask Top")
		(3 "B.Mask" user "Board Geometry/Soldermask Bottom")
		(17 "Dwgs.User" user "User.Drawings")
		(19 "Cmts.User" user "User.Comments")
		(21 "Eco1.User" user "User.Eco1")
		(23 "Eco2.User" user "User.Eco2")
		(25 "Edge.Cuts" user "Board Geometry/Outline")
		(27 "Margin" user)
		(31 "F.CrtYd" user "Package Geometry/Place Bound Top")
		(29 "B.CrtYd" user "Package Geometry/Place Bound Bottom")
		(35 "F.Fab" user "Ref Des/Assembly Top")
		(33 "B.Fab" user "Ref Des/Assembly Bottom")
	)
	(footprint ""
		(layer "F.Cu")
		(at 30.45968 -171.729908)
		(property "Reference" "J2"
			(at 7.63778 3.119628 0)
			(unlocked yes)
			(layer "F.SilkS")
			(effects
				(font
					(size 0.7874 0.5842)
					(thickness 0.1524)
				)
				(justify left)
			)
		)
		(property "Value" ""
			(at 0 0 0)
			(layer "F.Fab")
			(effects
				(font
					(size 1.27 1.27)
				)
			)
		)
		(duplicate_pad_numbers_are_jumpers no)
		(fp_line
			(start -2.135124 -4.560062)
			(end -2.135124 83.300062)
			(stroke
				(width 0.1524)
				(type default)
			)
			(layer "F.SilkS")
		)
		(fp_line
			(start -2.135124 83.300062)
			(end 7.215124 83.300062)
			(stroke
				(width 0.1524)
				(type default)
			)
			(layer "F.SilkS")
		)
		(fp_line
			(start 7.215124 -4.560062)
			(end -2.135124 -4.560062)
			(stroke
				(width 0.1524)
				(type default)
			)
			(layer "F.SilkS")
		)
		(fp_line
			(start 7.215124 83.300062)
			(end 7.215124 -4.560062)
			(stroke
				(width 0.1524)
				(type default)
			)
			(layer "F.SilkS")
		)
		(fp_poly
			(pts
				(xy -2.557272 -0.130556) (xy -5.257292 -0.83058) (xy -5.257292 0.569468)
			)
			(stroke
				(width 0)
				(type default)
			)
			(fill yes)
			(layer "F.SilkS")
		)
		(fp_poly
			(pts
				(xy -2.28219 -0.127) (xy -4.98221 -0.827024) (xy -4.98221 0.573024)
			)
			(stroke
				(width 0)
				(type default)
			)
			(fill yes)
			(layer "B.SilkS")
		)
		(fp_poly
			(pts
				(xy -0.8636 -0.8636) (xy -0.8636 79.6036) (xy -0.8636 79.629) (xy 5.9436 79.629) (xy 5.9436 79.6036)
				(xy 5.9436 -0.8636) (xy 5.9436 -0.889) (xy -0.8636 -0.889)
			)
			(stroke
				(width 0)
				(type default)
			)
			(fill no)
			(layer "B.CrtYd")
		)
		(fp_rect
			(start -2.135124 -4.560062)
			(end 7.21487 83.300062)
			(stroke
				(width 0)
				(type default)
			)
			(fill no)
			(layer "F.CrtYd")
		)
		(fp_line
			(start -2.135124 -4.560062)
			(end 7.215124 -4.560062)
			(stroke
				(width 0.1)
				(type default)
			)
			(layer "F.Fab")
		)
		(fp_line
			(start -2.135124 83.300062)
			(end -2.135124 -4.560062)
			(stroke
				(width 0.1)
				(type default)
			)
			(layer "F.Fab")
		)
		(fp_line
			(start 7.215124 -4.560062)
			(end 7.215124 83.300062)
			(stroke
				(width 0.1)
				(type default)
			)
			(layer "F.Fab")
		)
		(fp_line
			(start 7.215124 83.300062)
			(end -2.135124 83.300062)
			(stroke
				(width 0.1)
				(type default)
			)
			(layer "F.Fab")
		)
		(fp_text user "32"
			(at -3.674872 78.298802 0)
			(unlocked yes)
			(layer "F.SilkS")
			(effects
				(font
					(size 0.7874 0.5842)
					(thickness 0.1524)
				)
				(justify left)
			)
		)
		(fp_text user "1"
			(at -3.253994 -1.297178 0)
			(unlocked yes)
			(layer "F.SilkS")
			(effects
				(font
					(size 0.7874 0.5842)
					(thickness 0.1524)
				)
				(justify left)
			)
		)
		(fp_text user "64"
			(at 7.640066 -0.704342 0)
			(unlocked yes)
			(layer "F.SilkS")
			(effects
				(font
					(size 0.7874 0.5842)
					(thickness 0.1524)
				)
				(justify left)
			)
		)
		(fp_text user "33"
			(at 7.654544 83.258914 0)
			(unlocked yes)
			(layer "F.SilkS")
			(effects
				(font
					(size 0.7874 0.5842)
					(thickness 0.1524)
				)
				(justify left)
			)
		)
		(fp_text user "1"
			(at -1.619758 -0.610362 0)
			(unlocked yes)
			(layer "B.SilkS")
			(effects
				(font
					(size 0.7874 0.5842)
					(thickness 0.1524)
				)
				(justify left mirror)
			)
		)
		(fp_text user "32"
			(at -1.102868 78.932024 0)
			(unlocked yes)
			(layer "B.SilkS")
			(effects
				(font
					(size 0.7874 0.5842)
					(thickness 0.1524)
				)
				(justify left mirror)
			)
		)
		(fp_text user "64"
			(at 5.791454 -1.569466 0)
			(unlocked yes)
			(layer "B.SilkS")
			(effects
				(font
					(size 0.7874 0.5842)
					(thickness 0.1524)
				)
				(justify left mirror)
			)
		)
		(fp_text user "33"
			(at 6.84784 83.378294 0)
			(unlocked yes)
			(layer "B.SilkS")
			(effects
				(font
					(size 0.7874 0.5842)
					(thickness 0.1524)
				)
				(justify left mirror)
			)
		)
		(pad "1" thru_hole rect
			(at 0 0 270)
			(size 1.6256 1.6256)
			(drill 1.1176)
			(layers "*.Cu" "*.Mask")
			(remove_unused_layers no)
			(net "P12V")
			(clearance 0)
			(padstack
				(mode front_inner_back)
				(layer "Inner"
					(shape circle)
					(size 1.6256 1.6256)
					(clearance 0)
				)
				(layer "B.Cu"
					(shape rect)
					(size 1.6256 1.6256)
					(clearance 0)
				)
			)
		)
		(pad "2" thru_hole circle
			(at 0 2.54 270)
			(size 1.6256 1.6256)
			(drill 1.1176)
			(layers "*.Cu" "*.Mask")
			(remove_unused_layers no)
			(net "P12V")
			(clearance 0)
		)
		(pad "3" thru_hole circle
			(at 0 5.08 270)
			(size 1.6256 1.6256)
			(drill 1.1176)
			(layers "*.Cu" "*.Mask")
			(remove_unused_layers no)
			(net "P12V")
			(clearance 0)
		)
		(pad "4" thru_hole circle
			(at 0 7.62 270)
			(size 1.6256 1.6256)
			(drill 1.1176)
			(layers "*.Cu" "*.Mask")
			(remove_unused_layers no)
			(net "P12V")
			(clearance 0)
		)
		(pad "5" thru_hole circle
			(at 0 10.16 270)
			(size 1.6256 1.6256)
			(drill 1.1176)
			(layers "*.Cu" "*.Mask")
			(remove_unused_layers no)
			(net "P12V")
			(clearance 0)
		)
		(pad "6" thru_hole circle
			(at 0 12.7 270)
			(size 1.6256 1.6256)
			(drill 1.1176)
			(layers "*.Cu" "*.Mask")
			(remove_unused_layers no)
			(net "P12V")
			(clearance 0)
		)
		(pad "7" thru_hole circle
			(at 0 15.24 270)
			(size 1.6256 1.6256)
			(drill 1.1176)
			(layers "*.Cu" "*.Mask")
			(remove_unused_layers no)
			(net "P12V")
			(clearance 0)
		)
		(pad "8" thru_hole circle
			(at 0 17.78 270)
			(size 1.6256 1.6256)
			(drill 1.1176)
			(layers "*.Cu" "*.Mask")
			(remove_unused_layers no)
			(net "P12V")
			(clearance 0)
		)
		(pad "9" thru_hole circle
			(at 0 20.32 270)
			(size 1.6256 1.6256)
			(drill 1.1176)
			(layers "*.Cu" "*.Mask")
			(remove_unused_layers no)
			(net "P12V")
			(clearance 0)
		)
		(pad "10" thru_hole circle
			(at 0 22.86 270)
			(size 1.6256 1.6256)
			(drill 1.1176)
			(layers "*.Cu" "*.Mask")
			(remove_unused_layers no)
			(net "P12V")
			(clearance 0)
		)
		(pad "11" thru_hole circle
			(at 0 25.4 270)
			(size 1.6256 1.6256)
			(drill 1.1176)
			(layers "*.Cu" "*.Mask")
			(remove_unused_layers no)
			(net "P12V")
			(clearance 0)
		)
		(pad "12" thru_hole circle
			(at 0 27.94 270)
			(size 1.6256 1.6256)
			(drill 1.1176)
			(layers "*.Cu" "*.Mask")
			(remove_unused_layers no)
			(net "P12V")
			(clearance 0)
		)
		(pad "13" thru_hole circle
			(at 0 30.48 270)
			(size 1.6256 1.6256)
			(drill 1.1176)
			(layers "*.Cu" "*.Mask")
			(remove_unused_layers no)
			(net "GND")
			(clearance 0)
		)
		(pad "14" thru_hole circle
			(at 0 33.02 270)
			(size 1.6256 1.6256)
			(drill 1.1176)
			(layers "*.Cu" "*.Mask")
			(remove_unused_layers no)
			(net "GND")
			(clearance 0)
		)
		(pad "15" thru_hole circle
			(at 0 35.56 270)
			(size 1.6256 1.6256)
			(drill 1.1176)
			(layers "*.Cu" "*.Mask")
			(remove_unused_layers no)
			(net "GND")
			(clearance 0)
		)
		(pad "16" thru_hole circle
			(at 0 38.1 270)
			(size 1.6256 1.6256)
			(drill 1.1176)
			(layers "*.Cu" "*.Mask")
			(remove_unused_layers no)
			(net "GND")
			(clearance 0)
		)
		(pad "17" thru_hole circle
			(at 0 40.64 270)
			(size 1.6256 1.6256)
			(drill 1.1176)
			(layers "*.Cu" "*.Mask")
			(remove_unused_layers no)
			(net "GND")
			(clearance 0)
		)
		(pad "18" thru_hole circle
			(at 0 43.18 270)
			(size 1.6256 1.6256)
			(drill 1.1176)
			(layers "*.Cu" "*.Mask")
			(remove_unused_layers no)
			(net "GND")
			(clearance 0)
		)
		(pad "19" thru_hole circle
			(at 0 45.72 270)
			(size 1.6256 1.6256)
			(drill 1.1176)
			(layers "*.Cu" "*.Mask")
			(remove_unused_layers no)
			(net "GND")
			(clearance 0)
		)
		(pad "20" thru_hole circle
			(at 0 48.26 270)
			(size 1.6256 1.6256)
			(drill 1.1176)
			(layers "*.Cu" "*.Mask")
			(remove_unused_layers no)
			(net "GND")
			(clearance 0)
		)
		(pad "21" thru_hole circle
			(at 0 50.8 270)
			(size 1.6256 1.6256)
			(drill 1.1176)
			(layers "*.Cu" "*.Mask")
			(remove_unused_layers no)
			(net "GND")
			(clearance 0)
		)
		(pad "22" thru_hole circle
			(at 0 53.34 270)
			(size 1.6256 1.6256)
			(drill 1.1176)
			(layers "*.Cu" "*.Mask")
			(remove_unused_layers no)
			(net "GND")
			(clearance 0)
		)
		(pad "23" thru_hole circle
			(at 0 55.88 270)
			(size 1.6256 1.6256)
			(drill 1.1176)
			(layers "*.Cu" "*.Mask")
			(remove_unused_layers no)
			(net "GND")
			(clearance 0)
		)
		(pad "24" thru_hole circle
			(at 0 58.42 270)
			(size 1.6256 1.6256)
			(drill 1.1176)
			(layers "*.Cu" "*.Mask")
			(remove_unused_layers no)
			(net "GND")
			(clearance 0)
		)
		(pad "25" thru_hole circle
			(at 0 60.96 270)
			(size 1.6256 1.6256)
			(drill 1.1176)
			(layers "*.Cu" "*.Mask")
			(remove_unused_layers no)
			(net "Net_405")
			(clearance 0)
		)
		(pad "26" thru_hole circle
			(at 0 63.5 270)
			(size 1.6256 1.6256)
			(drill 1.1176)
			(layers "*.Cu" "*.Mask")
			(remove_unused_layers no)
			(net "PSU2_REMOTE_N")
			(clearance 0)
		)
		(pad "27" thru_hole circle
			(at 0 66.04 270)
			(size 1.6256 1.6256)
			(drill 1.1176)
			(layers "*.Cu" "*.Mask")
			(remove_unused_layers no)
			(net "PSU2_AC_OK")
			(clearance 0)
		)
		(pad "28" thru_hole circle
			(at 0 68.58 270)
			(size 1.6256 1.6256)
			(drill 1.1176)
			(layers "*.Cu" "*.Mask")
			(remove_unused_layers no)
			(net "PSU2_CSAHRE")
			(clearance 0)
		)
		(pad "29" thru_hole circle
			(at 0 71.12 270)
			(size 1.6256 1.6256)
			(drill 1.1176)
			(layers "*.Cu" "*.Mask")
			(remove_unused_layers no)
			(net "PSU2_PS_ON_N")
			(clearance 0)
		)
		(pad "30" thru_hole circle
			(at 0 73.66 270)
			(size 1.6256 1.6256)
			(drill 1.1176)
			(layers "*.Cu" "*.Mask")
			(remove_unused_layers no)
			(net "PSU2_PS_KILL")
			(clearance 0)
		)
		(pad "31" thru_hole circle
			(at 0 76.2 270)
			(size 1.6256 1.6256)
			(drill 1.1176)
			(layers "*.Cu" "*.Mask")
			(remove_unused_layers no)
			(net "PSU2_RESET")
			(clearance 0)
		)
		(pad "32" thru_hole circle
			(at 0 78.74 270)
			(size 1.6256 1.6256)
			(drill 1.1176)
			(layers "*.Cu" "*.Mask")
			(remove_unused_layers no)
			(net "PSU_ALERT_N")
			(clearance 0)
		)
		(pad "33" thru_hole circle
			(at 5.08 78.74 270)
			(size 1.6256 1.6256)
			(drill 1.1176)
			(layers "*.Cu" "*.Mask")
			(remove_unused_layers no)
			(net "I2C_PSU1_SDA")
			(clearance 0)
		)
		(pad "34" thru_hole circle
			(at 5.08 76.2 270)
			(size 1.6256 1.6256)
			(drill 1.1176)
			(layers "*.Cu" "*.Mask")
			(remove_unused_layers no)
			(net "Net_406")
			(clearance 0)
		)
		(pad "35" thru_hole circle
			(at 5.08 73.66 270)
			(size 1.6256 1.6256)
			(drill 1.1176)
			(layers "*.Cu" "*.Mask")
			(remove_unused_layers no)
			(net "I2C_PSU1_SCL")
			(clearance 0)
		)
		(pad "36" thru_hole circle
			(at 5.08 71.12 270)
			(size 1.6256 1.6256)
			(drill 1.1176)
			(layers "*.Cu" "*.Mask")
			(remove_unused_layers no)
			(net "PSU2_RETURN")
			(clearance 0)
		)
		(pad "37" thru_hole circle
			(at 5.08 68.58 270)
			(size 1.6256 1.6256)
			(drill 1.1176)
			(layers "*.Cu" "*.Mask")
			(remove_unused_layers no)
			(net "PSU2_DC_OK")
			(clearance 0)
		)
		(pad "38" thru_hole circle
			(at 5.08 66.04 270)
			(size 1.6256 1.6256)
			(drill 1.1176)
			(layers "*.Cu" "*.Mask")
			(remove_unused_layers no)
			(net "PSU2_AD0")
			(clearance 0)
		)
		(pad "39" thru_hole circle
			(at 5.08 63.5 270)
			(size 1.6256 1.6256)
			(drill 1.1176)
			(layers "*.Cu" "*.Mask")
			(remove_unused_layers no)
			(net "P12V_STBY")
			(clearance 0)
		)
		(pad "40" thru_hole circle
			(at 5.08 60.96 270)
			(size 1.6256 1.6256)
			(drill 1.1176)
			(layers "*.Cu" "*.Mask")
			(remove_unused_layers no)
			(net "PSU2_REMOTE_P")
			(clearance 0)
		)
		(pad "41" thru_hole circle
			(at 5.08 58.42 270)
			(size 1.6256 1.6256)
			(drill 1.1176)
			(layers "*.Cu" "*.Mask")
			(remove_unused_layers no)
			(net "GND")
			(clearance 0)
		)
		(pad "42" thru_hole circle
			(at 5.08 55.88 270)
			(size 1.6256 1.6256)
			(drill 1.1176)
			(layers "*.Cu" "*.Mask")
			(remove_unused_layers no)
			(net "GND")
			(clearance 0)
		)
		(pad "43" thru_hole circle
			(at 5.08 53.34 270)
			(size 1.6256 1.6256)
			(drill 1.1176)
			(layers "*.Cu" "*.Mask")
			(remove_unused_layers no)
			(net "GND")
			(clearance 0)
		)
		(pad "44" thru_hole circle
			(at 5.08 50.8 270)
			(size 1.6256 1.6256)
			(drill 1.1176)
			(layers "*.Cu" "*.Mask")
			(remove_unused_layers no)
			(net "GND")
			(clearance 0)
		)
		(pad "45" thru_hole circle
			(at 5.08 48.26 270)
			(size 1.6256 1.6256)
			(drill 1.1176)
			(layers "*.Cu" "*.Mask")
			(remove_unused_layers no)
			(net "GND")
			(clearance 0)
		)
		(pad "46" thru_hole circle
			(at 5.08 45.72 270)
			(size 1.6256 1.6256)
			(drill 1.1176)
			(layers "*.Cu" "*.Mask")
			(remove_unused_layers no)
			(net "GND")
			(clearance 0)
		)
		(pad "47" thru_hole circle
			(at 5.08 43.18 270)
			(size 1.6256 1.6256)
			(drill 1.1176)
			(layers "*.Cu" "*.Mask")
			(remove_unused_layers no)
			(net "GND")
			(clearance 0)
		)
		(pad "48" thru_hole circle
			(at 5.08 40.64 270)
			(size 1.6256 1.6256)
			(drill 1.1176)
			(layers "*.Cu" "*.Mask")
			(remove_unused_layers no)
			(net "GND")
			(clearance 0)
		)
		(pad "49" thru_hole circle
			(at 5.08 38.1 270)
			(size 1.6256 1.6256)
			(drill 1.1176)
			(layers "*.Cu" "*.Mask")
			(remove_unused_layers no)
			(net "GND")
			(clearance 0)
		)
		(pad "50" thru_hole circle
			(at 5.08 35.56 270)
			(size 1.6256 1.6256)
			(drill 1.1176)
			(layers "*.Cu" "*.Mask")
			(remove_unused_layers no)
			(net "GND")
			(clearance 0)
		)
		(pad "51" thru_hole circle
			(at 5.08 33.02 270)
			(size 1.6256 1.6256)
			(drill 1.1176)
			(layers "*.Cu" "*.Mask")
			(remove_unused_layers no)
			(net "GND")
			(clearance 0)
		)
		(pad "52" thru_hole circle
			(at 5.08 30.48 270)
			(size 1.6256 1.6256)
			(drill 1.1176)
			(layers "*.Cu" "*.Mask")
			(remove_unused_layers no)
			(net "GND")
			(clearance 0)
		)
		(pad "53" thru_hole circle
			(at 5.08 27.94 270)
			(size 1.6256 1.6256)
			(drill 1.1176)
			(layers "*.Cu" "*.Mask")
			(remove_unused_layers no)
			(net "P12V")
			(clearance 0)
		)
		(pad "54" thru_hole circle
			(at 5.08 25.4 270)
			(size 1.6256 1.6256)
			(drill 1.1176)
			(layers "*.Cu" "*.Mask")
			(remove_unused_layers no)
			(net "P12V")
			(clearance 0)
		)
		(pad "55" thru_hole circle
			(at 5.08 22.86 270)
			(size 1.6256 1.6256)
			(drill 1.1176)
			(layers "*.Cu" "*.Mask")
			(remove_unused_layers no)
			(net "P12V")
			(clearance 0)
		)
		(pad "56" thru_hole circle
			(at 5.08 20.32 270)
			(size 1.6256 1.6256)
			(drill 1.1176)
			(layers "*.Cu" "*.Mask")
			(remove_unused_layers no)
			(net "P12V")
			(clearance 0)
		)
		(pad "57" thru_hole circle
			(at 5.08 17.78 270)
			(size 1.6256 1.6256)
			(drill 1.1176)
			(layers "*.Cu" "*.Mask")
			(remove_unused_layers no)
			(net "P12V")
			(clearance 0)
		)
		(pad "58" thru_hole circle
			(at 5.08 15.24 270)
			(size 1.6256 1.6256)
			(drill 1.1176)
			(layers "*.Cu" "*.Mask")
			(remove_unused_layers no)
			(net "P12V")
			(clearance 0)
		)
		(pad "59" thru_hole circle
			(at 5.08 12.7 270)
			(size 1.6256 1.6256)
			(drill 1.1176)
			(layers "*.Cu" "*.Mask")
			(remove_unused_layers no)
			(net "P12V")
			(clearance 0)
		)
		(pad "60" thru_hole circle
			(at 5.08 10.16 270)
			(size 1.6256 1.6256)
			(drill 1.1176)
			(layers "*.Cu" "*.Mask")
			(remove_unused_layers no)
			(net "P12V")
			(clearance 0)
		)
		(pad "61" thru_hole circle
			(at 5.08 7.62 270)
			(size 1.6256 1.6256)
			(drill 1.1176)
			(layers "*.Cu" "*.Mask")
			(remove_unused_layers no)
			(net "P12V")
			(clearance 0)
		)
		(pad "62" thru_hole circle
			(at 5.08 5.08 270)
			(size 1.6256 1.6256)
			(drill 1.1176)
			(layers "*.Cu" "*.Mask")
			(remove_unused_layers no)
			(net "P12V")
			(clearance 0)
		)
		(pad "63" thru_hole circle
			(at 5.08 2.54 270)
			(size 1.6256 1.6256)
			(drill 1.1176)
			(layers "*.Cu" "*.Mask")
			(remove_unused_layers no)
			(net "P12V")
			(clearance 0)
		)
		(pad "64" thru_hole circle
			(at 5.08 0 270)
			(size 1.6256 1.6256)
			(drill 1.1176)
			(layers "*.Cu" "*.Mask")
			(remove_unused_layers no)
			(net "P12V")
			(clearance 0)
		)
	)
	(footprint ""
		(layer "F.Cu")
		(at 73.532746 -442.84646 90)
		(property "Reference" "C74"
			(at -3.89128 0.190754 90)
			(unlocked yes)
			(layer "F.SilkS")
			(effects
				(font
					(size 0.7874 0.5842)
					(thickness 0.1524)
				)
				(justify left)
			)
		)
		(property "Value" ""
			(at 0 0 90)
			(layer "F.Fab")
			(effects
				(font
					(size 1.27 1.27)
				)
			)
		)
		(duplicate_pad_numbers_are_jumpers no)
		(fp_line
			(start 0.7874 -0.4064)
			(end 0.7874 0.4064)
			(stroke
				(width 0.1524)
				(type default)
			)
			(layer "F.SilkS")
		)
		(fp_line
			(start -0.7874 -0.4064)
			(end 0.7874 -0.4064)
			(stroke
				(width 0.1524)
				(type default)
			)
			(layer "F.SilkS")
		)
		(fp_line
			(start 0 0.381)
			(end 0 -0.381)
			(stroke
				(width 0.1524)
				(type default)
			)
			(layer "F.SilkS")
		)
		(fp_line
			(start 0.7874 0.4064)
			(end -0.7874 0.4064)
			(stroke
				(width 0.1524)
				(type default)
			)
			(layer "F.SilkS")
		)
		(fp_line
			(start -0.7874 0.4064)
			(end -0.7874 -0.4064)
			(stroke
				(width 0.1524)
				(type default)
			)
			(layer "F.SilkS")
		)
		(fp_poly
			(pts
				(xy -0.5334 0.254) (xy -0.635 0.254) (xy -0.635 0.2286) (xy -0.635 -0.254) (xy -0.5334 -0.254) (xy -0.5334 -0.2794)
				(xy 0.5334 -0.2794) (xy 0.5334 -0.254) (xy 0.635 -0.254) (xy 0.635 0.254) (xy 0.5334 0.254) (xy 0.5334 0.2794)
				(xy -0.508 0.2794) (xy -0.5334 0.2794)
			)
			(stroke
				(width 0)
				(type default)
			)
			(fill no)
			(layer "F.CrtYd")
		)
		(pad "1" smd rect
			(at 0.40005 0 90)
			(size 0.4572 0.508)
			(layers "F.Cu" "F.Mask" "F.Paste")
			(net "P12V")
		)
		(pad "2" smd rect
			(at -0.40005 0 90)
			(size 0.4572 0.508)
			(layers "F.Cu" "F.Mask" "F.Paste")
			(net "GND")
		)
	)
)
